(kicad_pcb
	(version 20260206)
	(generator "pcbnew")
	(generator_version "10.0")
	(general
		(thickness 1.6)
		(legacy_teardrops no)
	)
	(paper "A4")
	(title_block
		(title "baseboard — 13948-1b.1110WZS1818.brd")
		(comment 1 "Honey Badger (Wiwynn) / footprints 132-139 of 2523")
	)
	(layers
		(0 "F.Cu" signal "TOP")
		(4 "In1.Cu" signal "L2GND")
		(6 "In2.Cu" signal "L3")
		(8 "In3.Cu" signal "L4VCC")
		(10 "In4.Cu" signal "L5VCC")
		(12 "In5.Cu" signal "L6")
		(14 "In6.Cu" signal "L7GND")
		(2 "B.Cu" signal "BOTTOM")
		(9 "F.Adhes" user "F.Adhesive")
		(11 "B.Adhes" user "B.Adhesive")
		(13 "F.Paste" user "Package Geometry/Pastemask Top")
		(15 "B.Paste" user "Package Geometry/Pastemask Bottom")
		(5 "F.SilkS" user "Ref Des/Silkscreen Top")
		(7 "B.SilkS" user "Ref Des/Silkscreen Bottom")
		(1 "F.Mask" user "Board Geometry/Soldermask Top")
		(3 "B.Mask" user "Board Geometry/Soldermask Bottom")
		(17 "Dwgs.User" user "User.Drawings")
		(19 "Cmts.User" user "User.Comments")
		(21 "Eco1.User" user "User.Eco1")
		(23 "Eco2.User" user "User.Eco2")
		(25 "Edge.Cuts" user "Board Geometry/Outline")
		(27 "Margin" user)
		(31 "F.CrtYd" user "Package Geometry/Place Bound Top")
		(29 "B.CrtYd" user "Package Geometry/Place Bound Bottom")
		(35 "F.Fab" user "Ref Des/Assembly Top")
		(33 "B.Fab" user "Ref Des/Assembly Bottom")
	)
	(footprint ""
		(layer "F.Cu")
		(at 35.56 -72.009 -90)
		(property "Reference" "R290"
			(at 0 0 270)
			(layer "F.SilkS")
			(hide yes)
			(effects
				(font
					(size 1.27 1.27)
				)
			)
		)
		(property "Value" "49D9R2F-GP"
			(at 0.064008 -3.993896 270)
			(unlocked yes)
			(layer "F.Fab")
			(hide yes)
			(effects
				(font
					(size 1.016 1.016)
					(thickness 0.1524)
				)
			)
		)
		(property "Device Type" "R402H16"
			(at 0.064008 -5.517896 270)
			(unlocked yes)
			(layer "F.Fab")
			(hide yes)
			(effects
				(font
					(size 1.016 1.016)
					(thickness 0.1524)
				)
			)
		)
		(duplicate_pad_numbers_are_jumpers no)
		(fp_line
			(start -0.508 -0.9398)
			(end -0.508 0.9398)
			(stroke
				(width 0.1524)
				(type default)
			)
			(layer "F.SilkS")
		)
		(fp_line
			(start 0.508 -0.9398)
			(end -0.508 -0.9398)
			(stroke
				(width 0.1524)
				(type default)
			)
			(layer "F.SilkS")
		)
		(fp_rect
			(start -0.508 0.9398)
			(end 0.508 -0.9398)
			(stroke
				(width 0)
				(type default)
			)
			(fill no)
			(layer "F.CrtYd")
		)
		(fp_rect
			(start -0.508 0.9398)
			(end 0.508 -0.9398)
			(stroke
				(width 0)
				(type default)
			)
			(fill no)
			(layer "F.Fab")
		)
		(pad "1" smd custom
			(at 0 -0.4445 270)
			(size 0.1397 0.1397)
			(layers "F.Cu" "F.Mask" "F.Paste")
			(net "P3V3")
			(options
				(clearance outline)
				(anchor circle)
			)
			(primitives
				(gr_poly
					(pts
						(arc
							(start -0.1778 -0.2794)
							(mid -0.249642 -0.249642)
							(end -0.2794 -0.1778)
						)
						(arc
							(start -0.2794 0.1778)
							(mid -0.249642 0.249642)
							(end -0.1778 0.2794)
						)
						(arc
							(start 0.1778 0.2794)
							(mid 0.249642 0.249642)
							(end 0.2794 0.1778)
						)
						(arc
							(start 0.2794 -0.1778)
							(mid 0.249642 -0.249642)
							(end 0.1778 -0.2794)
						)
					)
					(width 0)
					(fill yes)
				)
			)
		)
		(pad "2" smd custom
			(at 0 0.4445 270)
			(size 0.1397 0.1397)
			(layers "F.Cu" "F.Mask" "F.Paste")
			(net "INTA_LED_BLUE_C")
			(options
				(clearance outline)
				(anchor circle)
			)
			(primitives
				(gr_poly
					(pts
						(arc
							(start -0.1778 -0.2794)
							(mid -0.249642 -0.249642)
							(end -0.2794 -0.1778)
						)
						(arc
							(start -0.2794 0.1778)
							(mid -0.249642 0.249642)
							(end -0.1778 0.2794)
						)
						(arc
							(start 0.1778 0.2794)
							(mid 0.249642 0.249642)
							(end 0.2794 0.1778)
						)
						(arc
							(start 0.2794 -0.1778)
							(mid 0.249642 -0.249642)
							(end 0.1778 -0.2794)
						)
					)
					(width 0)
					(fill yes)
				)
			)
		)
	)
	(footprint ""
		(layer "F.Cu")
		(at 221.361 -104.013 90)
		(property "Reference" "PC148"
			(at 0 0 90)
			(layer "F.SilkS")
			(hide yes)
			(effects
				(font
					(size 1.27 1.27)
				)
			)
		)
		(property "Value" "SCD1U16V2KX-3GP"
			(at 1.1811 -2.7051 90)
			(unlocked yes)
			(layer "F.Fab")
			(hide yes)
			(effects
				(font
					(size 1.016 1.016)
					(thickness 0.1524)
				)
			)
		)
		(property "Device Type" "C402H22"
			(at 1.1811 -4.2291 90)
			(unlocked yes)
			(layer "F.Fab")
			(hide yes)
			(effects
				(font
					(size 1.016 1.016)
					(thickness 0.1524)
				)
			)
		)
		(duplicate_pad_numbers_are_jumpers no)
		(fp_rect
			(start -0.4318 0.9525)
			(end 0.4318 -0.9525)
			(stroke
				(width 0)
				(type default)
			)
			(fill no)
			(layer "F.CrtYd")
		)
		(fp_rect
			(start -0.4318 0.9525)
			(end 0.4318 -0.9525)
			(stroke
				(width 0)
				(type default)
			)
			(fill no)
			(layer "F.Fab")
		)
		(pad "1" smd custom
			(at 0 -0.4445 90)
			(size 0.1524 0.1524)
			(layers "F.Cu" "F.Mask" "F.Paste")
			(net "TPS74801_1V5_C_BIAS")
			(options
				(clearance outline)
				(anchor circle)
			)
			(primitives
				(gr_poly
					(pts
						(arc
							(start 0.3048 -0.2032)
							(mid 0.275042 -0.275042)
							(end 0.2032 -0.3048)
						)
						(arc
							(start -0.2032 -0.3048)
							(mid -0.275042 -0.275042)
							(end -0.3048 -0.2032)
						)
						(arc
							(start -0.3048 0.2032)
							(mid -0.275042 0.275042)
							(end -0.2032 0.3048)
						)
						(arc
							(start 0.2032 0.3048)
							(mid 0.275042 0.275042)
							(end 0.3048 0.2032)
						)
					)
					(width 0)
					(fill yes)
				)
			)
		)
		(pad "2" smd custom
			(at 0 0.4445 90)
			(size 0.1524 0.1524)
			(layers "F.Cu" "F.Mask" "F.Paste")
			(net "GND")
			(options
				(clearance outline)
				(anchor circle)
			)
			(primitives
				(gr_poly
					(pts
						(arc
							(start 0.3048 -0.2032)
							(mid 0.275042 -0.275042)
							(end 0.2032 -0.3048)
						)
						(arc
							(start -0.2032 -0.3048)
							(mid -0.275042 -0.275042)
							(end -0.3048 -0.2032)
						)
						(arc
							(start -0.3048 0.2032)
							(mid -0.275042 0.275042)
							(end -0.2032 0.3048)
						)
						(arc
							(start 0.2032 0.3048)
							(mid 0.275042 0.275042)
							(end 0.3048 0.2032)
						)
					)
					(width 0)
					(fill yes)
				)
			)
		)
	)
	(footprint ""
		(layer "F.Cu")
		(at 119.196612 -204.978)
		(property "Reference" "SR873"
			(at 0 0 0)
			(layer "F.SilkS")
			(hide yes)
			(effects
				(font
					(size 1.27 1.27)
				)
			)
		)
		(property "Value" "0R2J-2-GP"
			(at 0.064008 -3.993896 0)
			(unlocked yes)
			(layer "F.Fab")
			(hide yes)
			(effects
				(font
					(size 1.016 1.016)
					(thickness 0.1524)
				)
			)
		)
		(property "Device Type" "R402H16"
			(at 0.064008 -5.517896 0)
			(unlocked yes)
			(layer "F.Fab")
			(hide yes)
			(effects
				(font
					(size 1.016 1.016)
					(thickness 0.1524)
				)
			)
		)
		(duplicate_pad_numbers_are_jumpers no)
		(fp_line
			(start -0.508 -0.9398)
			(end -0.508 0.9398)
			(stroke
				(width 0.1524)
				(type default)
			)
			(layer "F.SilkS")
		)
		(fp_line
			(start 0.508 -0.9398)
			(end -0.508 -0.9398)
			(stroke
				(width 0.1524)
				(type default)
			)
			(layer "F.SilkS")
		)
		(fp_rect
			(start -0.508 0.9398)
			(end 0.508 -0.9398)
			(stroke
				(width 0)
				(type default)
			)
			(fill no)
			(layer "F.CrtYd")
		)
		(fp_rect
			(start -0.508 0.9398)
			(end 0.508 -0.9398)
			(stroke
				(width 0)
				(type default)
			)
			(fill no)
			(layer "F.Fab")
		)
		(pad "1" smd custom
			(at 0 -0.4445)
			(size 0.1397 0.1397)
			(layers "F.Cu" "F.Mask" "F.Paste")
			(net "SAS_HDD_REDV_TX7_N")
			(options
				(clearance outline)
				(anchor circle)
			)
			(primitives
				(gr_poly
					(pts
						(arc
							(start -0.1778 -0.2794)
							(mid -0.249642 -0.249642)
							(end -0.2794 -0.1778)
						)
						(arc
							(start -0.2794 0.1778)
							(mid -0.249642 0.249642)
							(end -0.1778 0.2794)
						)
						(arc
							(start 0.1778 0.2794)
							(mid 0.249642 0.249642)
							(end 0.2794 0.1778)
						)
						(arc
							(start 0.2794 -0.1778)
							(mid 0.249642 -0.249642)
							(end 0.1778 -0.2794)
						)
					)
					(width 0)
					(fill yes)
				)
			)
		)
		(pad "2" smd custom
			(at 0 0.4445)
			(size 0.1397 0.1397)
			(layers "F.Cu" "F.Mask" "F.Paste")
			(net "SAS_HDD_REDV_SER_TX7_N")
			(options
				(clearance outline)
				(anchor circle)
			)
			(primitives
				(gr_poly
					(pts
						(arc
							(start -0.1778 -0.2794)
							(mid -0.249642 -0.249642)
							(end -0.2794 -0.1778)
						)
						(arc
							(start -0.2794 0.1778)
							(mid -0.249642 0.249642)
							(end -0.1778 0.2794)
						)
						(arc
							(start 0.1778 0.2794)
							(mid 0.249642 0.249642)
							(end 0.2794 0.1778)
						)
						(arc
							(start 0.2794 -0.1778)
							(mid 0.249642 -0.249642)
							(end 0.1778 -0.2794)
						)
					)
					(width 0)
					(fill yes)
				)
			)
		)
	)
	(footprint ""
		(layer "F.Cu")
		(at 270.684752 -190.907416 180)
		(property "Reference" "R324"
			(at 0 0 180)
			(layer "F.SilkS")
			(hide yes)
			(effects
				(font
					(size 1.27 1.27)
				)
			)
		)
		(property "Value" "10KR2F-2-GP"
			(at 0.064008 -3.993896 180)
			(unlocked yes)
			(layer "F.Fab")
			(hide yes)
			(effects
				(font
					(size 1.016 1.016)
					(thickness 0.1524)
				)
			)
		)
		(property "Device Type" "R402H16"
			(at 0.064008 -5.517896 180)
			(unlocked yes)
			(layer "F.Fab")
			(hide yes)
			(effects
				(font
					(size 1.016 1.016)
					(thickness 0.1524)
				)
			)
		)
		(duplicate_pad_numbers_are_jumpers no)
		(fp_line
			(start 0.508 -0.9398)
			(end -0.508 -0.9398)
			(stroke
				(width 0.1524)
				(type default)
			)
			(layer "F.SilkS")
		)
		(fp_line
			(start -0.508 -0.9398)
			(end -0.508 0.9398)
			(stroke
				(width 0.1524)
				(type default)
			)
			(layer "F.SilkS")
		)
		(fp_rect
			(start -0.508 0.9398)
			(end 0.508 -0.9398)
			(stroke
				(width 0)
				(type default)
			)
			(fill no)
			(layer "F.CrtYd")
		)
		(fp_rect
			(start -0.508 0.9398)
			(end 0.508 -0.9398)
			(stroke
				(width 0)
				(type default)
			)
			(fill no)
			(layer "F.Fab")
		)
		(pad "1" smd custom
			(at 0 -0.4445 180)
			(size 0.1397 0.1397)
			(layers "F.Cu" "F.Mask" "F.Paste")
			(net "PECI0_R")
			(options
				(clearance outline)
				(anchor circle)
			)
			(primitives
				(gr_poly
					(pts
						(arc
							(start -0.1778 -0.2794)
							(mid -0.249642 -0.249642)
							(end -0.2794 -0.1778)
						)
						(arc
							(start -0.2794 0.1778)
							(mid -0.249642 0.249642)
							(end -0.1778 0.2794)
						)
						(arc
							(start 0.1778 0.2794)
							(mid 0.249642 0.249642)
							(end 0.2794 0.1778)
						)
						(arc
							(start 0.2794 -0.1778)
							(mid 0.249642 -0.249642)
							(end 0.1778 -0.2794)
						)
					)
					(width 0)
					(fill yes)
				)
			)
		)
		(pad "2" smd custom
			(at 0 0.4445 180)
			(size 0.1397 0.1397)
			(layers "F.Cu" "F.Mask" "F.Paste")
			(net "GND")
			(options
				(clearance outline)
				(anchor circle)
			)
			(primitives
				(gr_poly
					(pts
						(arc
							(start -0.1778 -0.2794)
							(mid -0.249642 -0.249642)
							(end -0.2794 -0.1778)
						)
						(arc
							(start -0.2794 0.1778)
							(mid -0.249642 0.249642)
							(end -0.1778 0.2794)
						)
						(arc
							(start 0.1778 0.2794)
							(mid 0.249642 0.249642)
							(end 0.2794 0.1778)
						)
						(arc
							(start 0.2794 -0.1778)
							(mid 0.249642 -0.249642)
							(end 0.1778 -0.2794)
						)
					)
					(width 0)
					(fill yes)
				)
			)
		)
	)
	(footprint ""
		(layer "F.Cu")
		(at 85.23097 -112.014 180)
		(property "Reference" "SC1229"
			(at 0 0 180)
			(layer "F.SilkS")
			(hide yes)
			(effects
				(font
					(size 1.27 1.27)
				)
			)
		)
		(property "Value" "SCD1U6D3V1KX-GP"
			(at -2.8321 -1.7399 180)
			(unlocked yes)
			(layer "F.Fab")
			(hide yes)
			(effects
				(font
					(size 1.016 1.016)
					(thickness 0.1524)
				)
			)
		)
		(property "Device Type" "C0201H13"
			(at -2.8321 -3.2639 180)
			(unlocked yes)
			(layer "F.Fab")
			(hide yes)
			(effects
				(font
					(size 1.016 1.016)
					(thickness 0.1524)
				)
			)
		)
		(duplicate_pad_numbers_are_jumpers no)
		(fp_rect
			(start -0.2794 0.6477)
			(end 0.2794 -0.6477)
			(stroke
				(width 0)
				(type default)
			)
			(fill no)
			(layer "F.CrtYd")
		)
		(fp_rect
			(start -0.2794 0.6477)
			(end 0.2794 -0.6477)
			(stroke
				(width 0)
				(type default)
			)
			(fill no)
			(layer "F.Fab")
		)
		(pad "1" smd custom
			(at 0 -0.2794 180)
			(size 0.0762 0.0762)
			(layers "F.Cu" "F.Mask" "F.Paste")
			(net "P1V8_E")
			(options
				(clearance outline)
				(anchor circle)
			)
			(primitives
				(gr_poly
					(pts
						(arc
							(start 0.1524 -0.127)
							(mid 0.137521 -0.162921)
							(end 0.1016 -0.1778)
						)
						(arc
							(start -0.1016 -0.1778)
							(mid -0.137521 -0.162921)
							(end -0.1524 -0.127)
						)
						(arc
							(start -0.1524 0.127)
							(mid -0.137521 0.162921)
							(end -0.1016 0.1778)
						)
						(arc
							(start 0.1016 0.1778)
							(mid 0.137521 0.162921)
							(end 0.1524 0.127)
						)
					)
					(width 0)
					(fill yes)
				)
			)
		)
		(pad "2" smd custom
			(at 0 0.2794 180)
			(size 0.0762 0.0762)
			(layers "F.Cu" "F.Mask" "F.Paste")
			(net "GND")
			(options
				(clearance outline)
				(anchor circle)
			)
			(primitives
				(gr_poly
					(pts
						(arc
							(start 0.1524 -0.127)
							(mid 0.137521 -0.162921)
							(end 0.1016 -0.1778)
						)
						(arc
							(start -0.1016 -0.1778)
							(mid -0.137521 -0.162921)
							(end -0.1524 -0.127)
						)
						(arc
							(start -0.1524 0.127)
							(mid -0.137521 0.162921)
							(end -0.1016 0.1778)
						)
						(arc
							(start 0.1016 0.1778)
							(mid 0.137521 0.162921)
							(end 0.1524 0.127)
						)
					)
					(width 0)
					(fill yes)
				)
			)
		)
	)
	(footprint ""
		(layer "F.Cu")
		(at 300.228 -163.322)
		(property "Reference" "TP94"
			(at 0 0 0)
			(layer "F.SilkS")
			(hide yes)
			(effects
				(font
					(size 1.27 1.27)
				)
			)
		)
		(property "Value" "TPAD28"
			(at 0.0127 -1.8034 0)
			(unlocked yes)
			(layer "F.Fab")
			(hide yes)
			(effects
				(font
					(size 1.016 1.016)
					(thickness 0.1524)
				)
			)
		)
		(property "Device Type" "TPAD28"
			(at 0.0127 -3.3274 0)
			(unlocked yes)
			(layer "F.Fab")
			(hide yes)
			(effects
				(font
					(size 1.016 1.016)
					(thickness 0.1524)
				)
			)
		)
		(duplicate_pad_numbers_are_jumpers no)
		(fp_poly
			(pts
				(arc
					(start 0.3556 0)
					(mid -0.3556 0)
					(end 0.3556 0)
				)
			)
			(stroke
				(width 0)
				(type default)
			)
			(fill no)
			(layer "F.CrtYd")
		)
		(fp_poly
			(pts
				(arc
					(start 0.6096 0)
					(mid -0.6096 0)
					(end 0.6096 0)
				)
			)
			(stroke
				(width 0)
				(type default)
			)
			(fill no)
			(layer "F.Fab")
		)
		(pad "1" smd circle
			(at 0 0)
			(size 0.7112 0.7112)
			(layers "F.Cu" "F.Mask" "F.Paste")
			(net "TP_GPIOH5")
		)
	)
	(footprint ""
		(layer "F.Cu")
		(at 67.437 -228.473 180)
		(property "Reference" "R2111"
			(at 0 0 180)
			(layer "F.SilkS")
			(hide yes)
			(effects
				(font
					(size 1.27 1.27)
				)
			)
		)
		(property "Value" "10R2J-2-GP"
			(at 0.064008 -3.993896 180)
			(unlocked yes)
			(layer "F.Fab")
			(hide yes)
			(effects
				(font
					(size 1.016 1.016)
					(thickness 0.1524)
				)
			)
		)
		(property "Device Type" "R402H14"
			(at 0.064008 -5.517896 180)
			(unlocked yes)
			(layer "F.Fab")
			(hide yes)
			(effects
				(font
					(size 1.016 1.016)
					(thickness 0.1524)
				)
			)
		)
		(duplicate_pad_numbers_are_jumpers no)
		(fp_line
			(start 0.508 -0.9398)
			(end -0.508 -0.9398)
			(stroke
				(width 0.1524)
				(type default)
			)
			(layer "F.SilkS")
		)
		(fp_line
			(start -0.508 -0.9398)
			(end -0.508 0.9398)
			(stroke
				(width 0.1524)
				(type default)
			)
			(layer "F.SilkS")
		)
		(fp_rect
			(start -0.508 0.9398)
			(end 0.508 -0.9398)
			(stroke
				(width 0)
				(type default)
			)
			(fill no)
			(layer "F.CrtYd")
		)
		(fp_rect
			(start -0.508 0.9398)
			(end 0.508 -0.9398)
			(stroke
				(width 0)
				(type default)
			)
			(fill no)
			(layer "F.Fab")
		)
		(pad "1" smd custom
			(at 0 -0.4445 180)
			(size 0.1397 0.1397)
			(layers "F.Cu" "F.Mask" "F.Paste")
			(net "MB0_12V_CTRL_GATE1")
			(options
				(clearance outline)
				(anchor circle)
			)
			(primitives
				(gr_poly
					(pts
						(arc
							(start -0.1778 -0.2794)
							(mid -0.249642 -0.249642)
							(end -0.2794 -0.1778)
						)
						(arc
							(start -0.2794 0.1778)
							(mid -0.249642 0.249642)
							(end -0.1778 0.2794)
						)
						(arc
							(start 0.1778 0.2794)
							(mid 0.249642 0.249642)
							(end 0.2794 0.1778)
						)
						(arc
							(start 0.2794 -0.1778)
							(mid 0.249642 -0.249642)
							(end 0.1778 -0.2794)
						)
					)
					(width 0)
					(fill yes)
				)
			)
		)
		(pad "2" smd custom
			(at 0 0.4445 180)
			(size 0.1397 0.1397)
			(layers "F.Cu" "F.Mask" "F.Paste")
			(net "MB0_CM_GATE_R")
			(options
				(clearance outline)
				(anchor circle)
			)
			(primitives
				(gr_poly
					(pts
						(arc
							(start -0.1778 -0.2794)
							(mid -0.249642 -0.249642)
							(end -0.2794 -0.1778)
						)
						(arc
							(start -0.2794 0.1778)
							(mid -0.249642 0.249642)
							(end -0.1778 0.2794)
						)
						(arc
							(start 0.1778 0.2794)
							(mid 0.249642 0.249642)
							(end 0.2794 0.1778)
						)
						(arc
							(start 0.2794 -0.1778)
							(mid 0.249642 -0.249642)
							(end 0.1778 -0.2794)
						)
					)
					(width 0)
					(fill yes)
				)
			)
		)
	)
	(footprint ""
		(layer "F.Cu")
		(at 278.003 -15.494 90)
		(property "Reference" "R545"
			(at 0 0 90)
			(layer "F.SilkS")
			(hide yes)
			(effects
				(font
					(size 1.27 1.27)
				)
			)
		)
		(property "Value" "0R3J-0-U-GP"
			(at -0.0254 -2.5146 90)
			(unlocked yes)
			(layer "F.Fab")
			(hide yes)
			(effects
				(font
					(size 1.016 1.016)
					(thickness 0.1524)
				)
			)
		)
		(property "Device Type" "R603H22"
			(at -0.0254 -4.0386 90)
			(unlocked yes)
			(layer "F.Fab")
			(hide yes)
			(effects
				(font
					(size 1.016 1.016)
					(thickness 0.1524)
				)
			)
		)
		(duplicate_pad_numbers_are_jumpers no)
		(fp_line
			(start 0.2032 0)
			(end 0.4826 0)
			(stroke
				(width 0.2032)
				(type default)
			)
			(layer "F.SilkS")
		)
		(fp_line
			(start -0.4826 0)
			(end -0.2032 0)
			(stroke
				(width 0.2032)
				(type default)
			)
			(layer "F.SilkS")
		)
		(fp_rect
			(start -0.5842 1.3335)
			(end 0.5842 -1.3335)
			(stroke
				(width 0)
				(type default)
			)
			(fill no)
			(layer "F.CrtYd")
		)
		(fp_rect
			(start -0.5842 1.3335)
			(end 0.5842 -1.3335)
			(stroke
				(width 0)
				(type default)
			)
			(fill no)
			(layer "F.Fab")
		)
		(pad "1" smd custom
			(at 0 -0.762 90)
			(size 0.2159 0.2159)
			(layers "F.Cu" "F.Mask" "F.Paste")
			(net "AGND_USB")
			(options
				(clearance outline)
				(anchor circle)
			)
			(primitives
				(gr_poly
					(pts
						(arc
							(start -0.3302 -0.4318)
							(mid -0.402042 -0.402042)
							(end -0.4318 -0.3302)
						)
						(arc
							(start -0.4318 0.3302)
							(mid -0.402042 0.402042)
							(end -0.3302 0.4318)
						)
						(arc
							(start 0.3302 0.4318)
							(mid 0.402042 0.402042)
							(end 0.4318 0.3302)
						)
						(arc
							(start 0.4318 -0.3302)
							(mid 0.402042 -0.402042)
							(end 0.3302 -0.4318)
						)
					)
					(width 0)
					(fill yes)
				)
			)
		)
		(pad "2" smd custom
			(at 0 0.762 90)
			(size 0.2159 0.2159)
			(layers "F.Cu" "F.Mask" "F.Paste")
			(net "GND")
			(options
				(clearance outline)
				(anchor circle)
			)
			(primitives
				(gr_poly
					(pts
						(arc
							(start -0.3302 -0.4318)
							(mid -0.402042 -0.402042)
							(end -0.4318 -0.3302)
						)
						(arc
							(start -0.4318 0.3302)
							(mid -0.402042 0.402042)
							(end -0.3302 0.4318)
						)
						(arc
							(start 0.3302 0.4318)
							(mid 0.402042 0.402042)
							(end 0.4318 0.3302)
						)
						(arc
							(start 0.4318 -0.3302)
							(mid 0.402042 -0.402042)
							(end 0.3302 -0.4318)
						)
					)
					(width 0)
					(fill yes)
				)
			)
		)
	)
)
